(kicad_pcb
	(version 20260206)
	(generator "pcbnew")
	(generator_version "10.0")
	(general
		(thickness 1.6)
		(legacy_teardrops no)
	)
	(paper "A4")
	(title_block
		(title "04192023_DAF0TMB3IC0_F0TG_MB_C_brd_V02_OCP.brd")
		(comment 1 "Grand Teton / footprints 2686-2691 of 8354")
	)
	(layers
		(0 "F.Cu" signal "TOP")
		(4 "In1.Cu" signal "GND")
		(6 "In2.Cu" signal "IN1")
		(8 "In3.Cu" signal "GND1")
		(10 "In4.Cu" signal "IN2")
		(12 "In5.Cu" signal "GND2")
		(14 "In6.Cu" signal "IN3")
		(16 "In7.Cu" signal "GND3")
		(18 "In8.Cu" signal "VCC")
		(20 "In9.Cu" signal "VCC1")
		(22 "In10.Cu" signal "GND4")
		(24 "In11.Cu" signal "IN4")
		(26 "In12.Cu" signal "GND5")
		(28 "In13.Cu" signal "IN5")
		(30 "In14.Cu" signal "GND6")
		(32 "In15.Cu" signal "IN6")
		(34 "In16.Cu" signal "GND7")
		(2 "B.Cu" signal "BOTTOM")
		(9 "F.Adhes" user "F.Adhesive")
		(11 "B.Adhes" user "B.Adhesive")
		(13 "F.Paste" user "Package Geometry/Pastemask Top")
		(15 "B.Paste" user "Package Geometry/Pastemask Bottom")
		(5 "F.SilkS" user "Ref Des/Silkscreen Top")
		(7 "B.SilkS" user "Ref Des/Silkscreen Bottom")
		(1 "F.Mask" user "Board Geometry/Soldermask Top")
		(3 "B.Mask" user "Board Geometry/Soldermask Bottom")
		(17 "Dwgs.User" user "User.Drawings")
		(19 "Cmts.User" user "User.Comments")
		(21 "Eco1.User" user "User.Eco1")
		(23 "Eco2.User" user "User.Eco2")
		(25 "Edge.Cuts" user "Board Geometry/Outline")
		(27 "Margin" user)
		(31 "F.CrtYd" user "Package Geometry/Place Bound Top")
		(29 "B.CrtYd" user "Package Geometry/Place Bound Bottom")
		(35 "F.Fab" user "Ref Des/Assembly Top")
		(33 "B.Fab" user "Ref Des/Assembly Bottom")
	)
	(footprint ""
		(layer "F.Cu")
		(at 10.7061 -394.22832 -90)
		(property "Reference" "PR6620"
			(at 0 0 270)
			(layer "F.SilkS")
			(hide yes)
			(effects
				(font
					(size 1.27 1.27)
				)
			)
		)
		(property "Value" ""
			(at 0 0 270)
			(layer "F.Fab")
			(effects
				(font
					(size 1.27 1.27)
				)
			)
		)
		(duplicate_pad_numbers_are_jumpers no)
		(fp_line
			(start -0.7874 0.4064)
			(end -0.7874 -0.4064)
			(stroke
				(width 0.1524)
				(type default)
			)
			(layer "F.SilkS")
		)
		(fp_line
			(start 0.7874 0.4064)
			(end -0.7874 0.4064)
			(stroke
				(width 0.1524)
				(type default)
			)
			(layer "F.SilkS")
		)
		(fp_line
			(start -0.7874 -0.4064)
			(end 0.7874 -0.4064)
			(stroke
				(width 0.1524)
				(type default)
			)
			(layer "F.SilkS")
		)
		(fp_line
			(start 0.7874 -0.4064)
			(end 0.7874 0.4064)
			(stroke
				(width 0.1524)
				(type default)
			)
			(layer "F.SilkS")
		)
		(fp_line
			(start -0.67945 0.3048)
			(end -0.67945 -0.305054)
			(stroke
				(width 0.1)
				(type default)
			)
			(layer "F.Fab")
		)
		(fp_line
			(start -0.12065 0.3048)
			(end -0.67945 0.3048)
			(stroke
				(width 0.1)
				(type default)
			)
			(layer "F.Fab")
		)
		(fp_line
			(start 0.120396 0.3048)
			(end 0.120396 0.2794)
			(stroke
				(width 0.1)
				(type default)
			)
			(layer "F.Fab")
		)
		(fp_line
			(start 0.67945 0.3048)
			(end 0.120396 0.3048)
			(stroke
				(width 0.1)
				(type default)
			)
			(layer "F.Fab")
		)
		(fp_line
			(start -0.12065 0.2794)
			(end -0.12065 0.3048)
			(stroke
				(width 0.1)
				(type default)
			)
			(layer "F.Fab")
		)
		(fp_line
			(start 0.120396 0.2794)
			(end -0.12065 0.2794)
			(stroke
				(width 0.1)
				(type default)
			)
			(layer "F.Fab")
		)
		(fp_line
			(start -0.12065 -0.2794)
			(end 0.12065 -0.2794)
			(stroke
				(width 0.1)
				(type default)
			)
			(layer "F.Fab")
		)
		(fp_line
			(start 0.12065 -0.2794)
			(end 0.12065 -0.3048)
			(stroke
				(width 0.1)
				(type default)
			)
			(layer "F.Fab")
		)
		(fp_line
			(start 0.12065 -0.3048)
			(end 0.67945 -0.3048)
			(stroke
				(width 0.1)
				(type default)
			)
			(layer "F.Fab")
		)
		(fp_line
			(start 0.67945 -0.3048)
			(end 0.67945 0.3048)
			(stroke
				(width 0.1)
				(type default)
			)
			(layer "F.Fab")
		)
		(fp_line
			(start -0.67945 -0.305054)
			(end -0.12065 -0.305054)
			(stroke
				(width 0.1)
				(type default)
			)
			(layer "F.Fab")
		)
		(fp_line
			(start -0.12065 -0.305054)
			(end -0.12065 -0.2794)
			(stroke
				(width 0.1)
				(type default)
			)
			(layer "F.Fab")
		)
		(pad "1" smd circle
			(at -0.40005 0 270)
			(size 0 0)
			(layers "F.Cu" "F.Mask" "F.Paste")
			(net "P3V3_AUX")
		)
		(pad "2" smd circle
			(at 0.40005 0 270)
			(size 0 0)
			(layers "F.Cu" "F.Mask" "F.Paste")
			(net "P0V9_RETIMER_CPU1_PVCC")
		)
	)
	(footprint ""
		(layer "F.Cu")
		(at 46.16704 -434.057552 -90)
		(property "Reference" "R3509"
			(at 0 0 270)
			(layer "F.SilkS")
			(hide yes)
			(effects
				(font
					(size 1.27 1.27)
				)
			)
		)
		(property "Value" ""
			(at 0 0 270)
			(layer "F.Fab")
			(effects
				(font
					(size 1.27 1.27)
				)
			)
		)
		(duplicate_pad_numbers_are_jumpers no)
		(fp_line
			(start -0.7874 0.4064)
			(end -0.7874 -0.4064)
			(stroke
				(width 0.1524)
				(type default)
			)
			(layer "F.SilkS")
		)
		(fp_line
			(start 0.7874 0.4064)
			(end -0.7874 0.4064)
			(stroke
				(width 0.1524)
				(type default)
			)
			(layer "F.SilkS")
		)
		(fp_line
			(start -0.7874 -0.4064)
			(end 0.7874 -0.4064)
			(stroke
				(width 0.1524)
				(type default)
			)
			(layer "F.SilkS")
		)
		(fp_line
			(start 0.7874 -0.4064)
			(end 0.7874 0.4064)
			(stroke
				(width 0.1524)
				(type default)
			)
			(layer "F.SilkS")
		)
		(fp_line
			(start -0.67945 0.3048)
			(end -0.67945 -0.305054)
			(stroke
				(width 0.1)
				(type default)
			)
			(layer "F.Fab")
		)
		(fp_line
			(start -0.12065 0.3048)
			(end -0.67945 0.3048)
			(stroke
				(width 0.1)
				(type default)
			)
			(layer "F.Fab")
		)
		(fp_line
			(start 0.120396 0.3048)
			(end 0.120396 0.2794)
			(stroke
				(width 0.1)
				(type default)
			)
			(layer "F.Fab")
		)
		(fp_line
			(start 0.67945 0.3048)
			(end 0.120396 0.3048)
			(stroke
				(width 0.1)
				(type default)
			)
			(layer "F.Fab")
		)
		(fp_line
			(start -0.12065 0.2794)
			(end -0.12065 0.3048)
			(stroke
				(width 0.1)
				(type default)
			)
			(layer "F.Fab")
		)
		(fp_line
			(start 0.120396 0.2794)
			(end -0.12065 0.2794)
			(stroke
				(width 0.1)
				(type default)
			)
			(layer "F.Fab")
		)
		(fp_line
			(start -0.12065 -0.2794)
			(end 0.12065 -0.2794)
			(stroke
				(width 0.1)
				(type default)
			)
			(layer "F.Fab")
		)
		(fp_line
			(start 0.12065 -0.2794)
			(end 0.12065 -0.3048)
			(stroke
				(width 0.1)
				(type default)
			)
			(layer "F.Fab")
		)
		(fp_line
			(start 0.12065 -0.3048)
			(end 0.67945 -0.3048)
			(stroke
				(width 0.1)
				(type default)
			)
			(layer "F.Fab")
		)
		(fp_line
			(start 0.67945 -0.3048)
			(end 0.67945 0.3048)
			(stroke
				(width 0.1)
				(type default)
			)
			(layer "F.Fab")
		)
		(fp_line
			(start -0.67945 -0.305054)
			(end -0.12065 -0.305054)
			(stroke
				(width 0.1)
				(type default)
			)
			(layer "F.Fab")
		)
		(fp_line
			(start -0.12065 -0.305054)
			(end -0.12065 -0.2794)
			(stroke
				(width 0.1)
				(type default)
			)
			(layer "F.Fab")
		)
		(pad "1" smd circle
			(at -0.40005 0 270)
			(size 0 0)
			(layers "F.Cu" "F.Mask" "F.Paste")
			(net "GPU_FPGA_RST_R1_BUF_N")
		)
		(pad "2" smd circle
			(at 0.40005 0 270)
			(size 0 0)
			(layers "F.Cu" "F.Mask" "F.Paste")
			(net "GND")
		)
	)
	(footprint ""
		(layer "F.Cu")
		(at 24.765 -365.76 180)
		(property "Reference" "C8360"
			(at 0 0 180)
			(layer "F.SilkS")
			(hide yes)
			(effects
				(font
					(size 1.27 1.27)
				)
			)
		)
		(property "Value" ""
			(at 0 0 180)
			(layer "F.Fab")
			(effects
				(font
					(size 1.27 1.27)
				)
			)
		)
		(duplicate_pad_numbers_are_jumpers no)
		(fp_line
			(start 0.7874 0.4064)
			(end -0.7874 0.4064)
			(stroke
				(width 0.1524)
				(type default)
			)
			(layer "F.SilkS")
		)
		(fp_line
			(start 0.7874 -0.4064)
			(end 0.7874 0.4064)
			(stroke
				(width 0.1524)
				(type default)
			)
			(layer "F.SilkS")
		)
		(fp_line
			(start -0.7874 0.4064)
			(end -0.7874 -0.4064)
			(stroke
				(width 0.1524)
				(type default)
			)
			(layer "F.SilkS")
		)
		(fp_line
			(start -0.7874 -0.4064)
			(end 0.7874 -0.4064)
			(stroke
				(width 0.1524)
				(type default)
			)
			(layer "F.SilkS")
		)
		(fp_line
			(start 0.67945 0.3048)
			(end 0.120396 0.3048)
			(stroke
				(width 0.1)
				(type default)
			)
			(layer "F.Fab")
		)
		(fp_line
			(start 0.67945 -0.3048)
			(end 0.67945 0.3048)
			(stroke
				(width 0.1)
				(type default)
			)
			(layer "F.Fab")
		)
		(fp_line
			(start 0.12065 -0.2794)
			(end 0.12065 -0.3048)
			(stroke
				(width 0.1)
				(type default)
			)
			(layer "F.Fab")
		)
		(fp_line
			(start 0.12065 -0.3048)
			(end 0.67945 -0.3048)
			(stroke
				(width 0.1)
				(type default)
			)
			(layer "F.Fab")
		)
		(fp_line
			(start 0.120396 0.3048)
			(end 0.120396 0.2794)
			(stroke
				(width 0.1)
				(type default)
			)
			(layer "F.Fab")
		)
		(fp_line
			(start 0.120396 0.2794)
			(end -0.12065 0.2794)
			(stroke
				(width 0.1)
				(type default)
			)
			(layer "F.Fab")
		)
		(fp_line
			(start -0.12065 0.3048)
			(end -0.67945 0.3048)
			(stroke
				(width 0.1)
				(type default)
			)
			(layer "F.Fab")
		)
		(fp_line
			(start -0.12065 0.2794)
			(end -0.12065 0.3048)
			(stroke
				(width 0.1)
				(type default)
			)
			(layer "F.Fab")
		)
		(fp_line
			(start -0.12065 -0.2794)
			(end 0.12065 -0.2794)
			(stroke
				(width 0.1)
				(type default)
			)
			(layer "F.Fab")
		)
		(fp_line
			(start -0.12065 -0.305054)
			(end -0.12065 -0.2794)
			(stroke
				(width 0.1)
				(type default)
			)
			(layer "F.Fab")
		)
		(fp_line
			(start -0.67945 0.3048)
			(end -0.67945 -0.305054)
			(stroke
				(width 0.1)
				(type default)
			)
			(layer "F.Fab")
		)
		(fp_line
			(start -0.67945 -0.305054)
			(end -0.12065 -0.305054)
			(stroke
				(width 0.1)
				(type default)
			)
			(layer "F.Fab")
		)
		(pad "1" smd circle
			(at -0.40005 0 180)
			(size 0 0)
			(layers "F.Cu" "F.Mask" "F.Paste")
			(net "PWRGD_PVDDCR_CPU1_P1_R")
		)
		(pad "2" smd circle
			(at 0.40005 0 180)
			(size 0 0)
			(layers "F.Cu" "F.Mask" "F.Paste")
			(net "GND")
		)
	)
	(footprint ""
		(layer "F.Cu")
		(at 418.21354 -109.231176 90)
		(property "Reference" "PC2161"
			(at 0 0 90)
			(layer "F.SilkS")
			(hide yes)
			(effects
				(font
					(size 1.27 1.27)
				)
			)
		)
		(property "Value" ""
			(at 0 0 90)
			(layer "F.Fab")
			(effects
				(font
					(size 1.27 1.27)
				)
			)
		)
		(duplicate_pad_numbers_are_jumpers no)
		(fp_line
			(start 0.7874 -0.4064)
			(end 0.7874 0.4064)
			(stroke
				(width 0.1524)
				(type default)
			)
			(layer "F.SilkS")
		)
		(fp_line
			(start -0.7874 -0.4064)
			(end 0.7874 -0.4064)
			(stroke
				(width 0.1524)
				(type default)
			)
			(layer "F.SilkS")
		)
		(fp_line
			(start 0.7874 0.4064)
			(end -0.7874 0.4064)
			(stroke
				(width 0.1524)
				(type default)
			)
			(layer "F.SilkS")
		)
		(fp_line
			(start -0.7874 0.4064)
			(end -0.7874 -0.4064)
			(stroke
				(width 0.1524)
				(type default)
			)
			(layer "F.SilkS")
		)
		(fp_line
			(start -0.12065 -0.305054)
			(end -0.12065 -0.2794)
			(stroke
				(width 0.1)
				(type default)
			)
			(layer "F.Fab")
		)
		(fp_line
			(start -0.67945 -0.305054)
			(end -0.12065 -0.305054)
			(stroke
				(width 0.1)
				(type default)
			)
			(layer "F.Fab")
		)
		(fp_line
			(start 0.67945 -0.3048)
			(end 0.67945 0.3048)
			(stroke
				(width 0.1)
				(type default)
			)
			(layer "F.Fab")
		)
		(fp_line
			(start 0.12065 -0.3048)
			(end 0.67945 -0.3048)
			(stroke
				(width 0.1)
				(type default)
			)
			(layer "F.Fab")
		)
		(fp_line
			(start 0.12065 -0.2794)
			(end 0.12065 -0.3048)
			(stroke
				(width 0.1)
				(type default)
			)
			(layer "F.Fab")
		)
		(fp_line
			(start -0.12065 -0.2794)
			(end 0.12065 -0.2794)
			(stroke
				(width 0.1)
				(type default)
			)
			(layer "F.Fab")
		)
		(fp_line
			(start 0.120396 0.2794)
			(end -0.12065 0.2794)
			(stroke
				(width 0.1)
				(type default)
			)
			(layer "F.Fab")
		)
		(fp_line
			(start -0.12065 0.2794)
			(end -0.12065 0.3048)
			(stroke
				(width 0.1)
				(type default)
			)
			(layer "F.Fab")
		)
		(fp_line
			(start 0.67945 0.3048)
			(end 0.120396 0.3048)
			(stroke
				(width 0.1)
				(type default)
			)
			(layer "F.Fab")
		)
		(fp_line
			(start 0.120396 0.3048)
			(end 0.120396 0.2794)
			(stroke
				(width 0.1)
				(type default)
			)
			(layer "F.Fab")
		)
		(fp_line
			(start -0.12065 0.3048)
			(end -0.67945 0.3048)
			(stroke
				(width 0.1)
				(type default)
			)
			(layer "F.Fab")
		)
		(fp_line
			(start -0.67945 0.3048)
			(end -0.67945 -0.305054)
			(stroke
				(width 0.1)
				(type default)
			)
			(layer "F.Fab")
		)
		(pad "1" smd circle
			(at -0.40005 0 90)
			(size 0 0)
			(layers "F.Cu" "F.Mask" "F.Paste")
			(net "P3V3_OCP_DVDT_1")
		)
		(pad "2" smd circle
			(at 0.40005 0 90)
			(size 0 0)
			(layers "F.Cu" "F.Mask" "F.Paste")
			(net "GND")
		)
	)
	(footprint ""
		(layer "F.Cu")
		(at 328.699876 -70.098412 90)
		(property "Reference" "D76"
			(at -3.934714 -0.691642 90)
			(unlocked yes)
			(layer "F.SilkS")
			(effects
				(font
					(size 0.7874 0.5842)
					(thickness 0.1524)
				)
				(justify left)
			)
		)
		(property "Value" ""
			(at 0 0 90)
			(layer "F.Fab")
			(effects
				(font
					(size 1.27 1.27)
				)
			)
		)
		(duplicate_pad_numbers_are_jumpers no)
		(fp_line
			(start 1.16078 -0.4826)
			(end 1.16078 0.4826)
			(stroke
				(width 0.1524)
				(type default)
			)
			(layer "F.SilkS")
		)
		(fp_line
			(start 1.03378 -0.4826)
			(end 1.03378 0.4826)
			(stroke
				(width 0.1524)
				(type default)
			)
			(layer "F.SilkS")
		)
		(fp_line
			(start 0.90678 -0.4826)
			(end 0.90678 0.4826)
			(stroke
				(width 0.1524)
				(type default)
			)
			(layer "F.SilkS")
		)
		(fp_line
			(start -0.64008 -0.4826)
			(end 1.16078 -0.4826)
			(stroke
				(width 0.1524)
				(type default)
			)
			(layer "F.SilkS")
		)
		(fp_line
			(start -0.79248 -0.4826)
			(end 1.03378 -0.4826)
			(stroke
				(width 0.1524)
				(type default)
			)
			(layer "F.SilkS")
		)
		(fp_line
			(start -0.89408 -0.4826)
			(end 0.90678 -0.4826)
			(stroke
				(width 0.1524)
				(type default)
			)
			(layer "F.SilkS")
		)
		(fp_line
			(start 1.16078 0.4826)
			(end -0.64008 0.4826)
			(stroke
				(width 0.1524)
				(type default)
			)
			(layer "F.SilkS")
		)
		(fp_line
			(start 1.03378 0.4826)
			(end -0.79248 0.4826)
			(stroke
				(width 0.1524)
				(type default)
			)
			(layer "F.SilkS")
		)
		(fp_line
			(start 0.90678 0.4826)
			(end -0.90678 0.4826)
			(stroke
				(width 0.1524)
				(type default)
			)
			(layer "F.SilkS")
		)
		(fp_line
			(start -0.90678 0.4826)
			(end -0.90678 -0.4699)
			(stroke
				(width 0.1524)
				(type default)
			)
			(layer "F.SilkS")
		)
		(fp_line
			(start 0.499872 -0.249936)
			(end 0.499872 0.249936)
			(stroke
				(width 0.1)
				(type default)
			)
			(layer "F.Fab")
		)
		(fp_line
			(start -0.499872 -0.249936)
			(end 0.499872 -0.249936)
			(stroke
				(width 0.1)
				(type default)
			)
			(layer "F.Fab")
		)
		(fp_line
			(start 0.499872 0.249936)
			(end -0.499872 0.249936)
			(stroke
				(width 0.1)
				(type default)
			)
			(layer "F.Fab")
		)
		(fp_line
			(start -0.499872 0.249936)
			(end -0.499872 -0.249936)
			(stroke
				(width 0.1)
				(type default)
			)
			(layer "F.Fab")
		)
		(pad "A" smd rect
			(at -0.47498 0 90)
			(size 0.6096 0.7112)
			(layers "F.Cu" "F.Mask" "F.Paste")
			(net "LED_PWRGD_PVDDCR_CPU1_P0_R")
		)
		(pad "C" smd rect
			(at 0.47498 0 90)
			(size 0.6096 0.7112)
			(layers "F.Cu" "F.Mask" "F.Paste")
			(net "LED_PWRGD_PVDDCR_CPU1_P0_D")
		)
	)
	(footprint ""
		(layer "F.Cu")
		(at 132.715 -109.474 -90)
		(property "Reference" "R8115"
			(at 0 0 270)
			(layer "F.SilkS")
			(hide yes)
			(effects
				(font
					(size 1.27 1.27)
				)
			)
		)
		(property "Value" ""
			(at 0 0 270)
			(layer "F.Fab")
			(effects
				(font
					(size 1.27 1.27)
				)
			)
		)
		(duplicate_pad_numbers_are_jumpers no)
		(fp_line
			(start -0.7874 0.4064)
			(end -0.7874 -0.4064)
			(stroke
				(width 0.1524)
				(type default)
			)
			(layer "F.SilkS")
		)
		(fp_line
			(start 0.7874 0.4064)
			(end -0.7874 0.4064)
			(stroke
				(width 0.1524)
				(type default)
			)
			(layer "F.SilkS")
		)
		(fp_line
			(start -0.7874 -0.4064)
			(end 0.7874 -0.4064)
			(stroke
				(width 0.1524)
				(type default)
			)
			(layer "F.SilkS")
		)
		(fp_line
			(start 0.7874 -0.4064)
			(end 0.7874 0.4064)
			(stroke
				(width 0.1524)
				(type default)
			)
			(layer "F.SilkS")
		)
		(fp_line
			(start -0.67945 0.3048)
			(end -0.67945 -0.305054)
			(stroke
				(width 0.1)
				(type default)
			)
			(layer "F.Fab")
		)
		(fp_line
			(start -0.12065 0.3048)
			(end -0.67945 0.3048)
			(stroke
				(width 0.1)
				(type default)
			)
			(layer "F.Fab")
		)
		(fp_line
			(start 0.120396 0.3048)
			(end 0.120396 0.2794)
			(stroke
				(width 0.1)
				(type default)
			)
			(layer "F.Fab")
		)
		(fp_line
			(start 0.67945 0.3048)
			(end 0.120396 0.3048)
			(stroke
				(width 0.1)
				(type default)
			)
			(layer "F.Fab")
		)
		(fp_line
			(start -0.12065 0.2794)
			(end -0.12065 0.3048)
			(stroke
				(width 0.1)
				(type default)
			)
			(layer "F.Fab")
		)
		(fp_line
			(start 0.120396 0.2794)
			(end -0.12065 0.2794)
			(stroke
				(width 0.1)
				(type default)
			)
			(layer "F.Fab")
		)
		(fp_line
			(start -0.12065 -0.2794)
			(end 0.12065 -0.2794)
			(stroke
				(width 0.1)
				(type default)
			)
			(layer "F.Fab")
		)
		(fp_line
			(start 0.12065 -0.2794)
			(end 0.12065 -0.3048)
			(stroke
				(width 0.1)
				(type default)
			)
			(layer "F.Fab")
		)
		(fp_line
			(start 0.12065 -0.3048)
			(end 0.67945 -0.3048)
			(stroke
				(width 0.1)
				(type default)
			)
			(layer "F.Fab")
		)
		(fp_line
			(start 0.67945 -0.3048)
			(end 0.67945 0.3048)
			(stroke
				(width 0.1)
				(type default)
			)
			(layer "F.Fab")
		)
		(fp_line
			(start -0.67945 -0.305054)
			(end -0.12065 -0.305054)
			(stroke
				(width 0.1)
				(type default)
			)
			(layer "F.Fab")
		)
		(fp_line
			(start -0.12065 -0.305054)
			(end -0.12065 -0.2794)
			(stroke
				(width 0.1)
				(type default)
			)
			(layer "F.Fab")
		)
		(pad "1" smd circle
			(at -0.40005 0 270)
			(size 0 0)
			(layers "F.Cu" "F.Mask" "F.Paste")
			(net "P12V_AUX_UV_ADR_TRIGGER")
		)
		(pad "2" smd circle
			(at 0.40005 0 270)
			(size 0 0)
			(layers "F.Cu" "F.Mask" "F.Paste")
			(net "GND")
		)
	)
)
